(kicad_pcb
	(version 20260206)
	(generator "pcbnew")
	(generator_version "10.0")
	(general
		(thickness 1.6)
		(legacy_teardrops no)
	)
	(paper "A4")
	(title_block
		(title "03242023_DA0F0TMBIJ0_F0T_Motherboard_J_brd_V01_OCP.brd")
		(comment 1 "Grand Teton / footprint 3039 of 6105 (U2), pads 1820-1927 of 4677")
	)
	(layers
		(0 "F.Cu" signal "TOP")
		(4 "In1.Cu" signal "GND")
		(6 "In2.Cu" signal "IN1")
		(8 "In3.Cu" signal "GND1")
		(10 "In4.Cu" signal "IN2")
		(12 "In5.Cu" signal "GND2")
		(14 "In6.Cu" signal "IN3")
		(16 "In7.Cu" signal "GND3")
		(18 "In8.Cu" signal "VCC")
		(20 "In9.Cu" signal "VCC1")
		(22 "In10.Cu" signal "GND4")
		(24 "In11.Cu" signal "IN4")
		(26 "In12.Cu" signal "GND5")
		(28 "In13.Cu" signal "IN5")
		(30 "In14.Cu" signal "GND6")
		(32 "In15.Cu" signal "IN6")
		(34 "In16.Cu" signal "GND7")
		(2 "B.Cu" signal "BOTTOM")
		(9 "F.Adhes" user "F.Adhesive")
		(11 "B.Adhes" user "B.Adhesive")
		(13 "F.Paste" user "Package Geometry/Pastemask Top")
		(15 "B.Paste" user "Package Geometry/Pastemask Bottom")
		(5 "F.SilkS" user "Ref Des/Silkscreen Top")
		(7 "B.SilkS" user "Ref Des/Silkscreen Bottom")
		(1 "F.Mask" user "Board Geometry/Soldermask Top")
		(3 "B.Mask" user "Board Geometry/Soldermask Bottom")
		(17 "Dwgs.User" user "User.Drawings")
		(19 "Cmts.User" user "User.Comments")
		(21 "Eco1.User" user "User.Eco1")
		(23 "Eco2.User" user "User.Eco2")
		(25 "Edge.Cuts" user "Board Geometry/Outline")
		(27 "Margin" user)
		(31 "F.CrtYd" user "Package Geometry/Place Bound Top")
		(29 "B.CrtYd" user "Package Geometry/Place Bound Bottom")
		(35 "F.Fab" user "Ref Des/Assembly Top")
		(33 "B.Fab" user "Ref Des/Assembly Bottom")
	)
	(footprint ""
		(layer "F.Cu")
		(at 359.870248 -251.76988 90)
		(property "Reference" "U2"
			(at -74.416158 -44.488608 0)
			(unlocked yes)
			(layer "F.SilkS")
			(effects
				(font
					(size 1.6002 1.1938)
					(thickness 0.1524)
				)
				(justify left)
			)
		)
		(property "Value" ""
			(at 0 0 90)
			(layer "F.Fab")
			(effects
				(font
					(size 1.27 1.27)
				)
			)
		)
		(duplicate_pad_numbers_are_jumpers no)
		(pad "CD24" smd circle
			(at -18.705576 2.529586 270)
			(size 0.4318 0.4318)
			(layers "F.Cu" "F.Mask" "F.Paste")
			(net "TP_H_SBLINK4_CPU0_PMDOWN")
		)
		(pad "CD26" smd circle
			(at -17.07769 2.529586 270)
			(size 0.4318 0.4318)
			(layers "F.Cu" "F.Mask" "F.Paste")
			(net "NC_CPU0_MDFI_DIE10_EW0")
		)
		(pad "CD28" smd circle
			(at -15.450058 2.529586 270)
			(size 0.4318 0.4318)
			(layers "F.Cu" "F.Mask" "F.Paste")
			(net "TP_TRC_CPU0_PTI_MON<1>")
		)
		(pad "CD30" smd circle
			(at -13.822426 2.529586 270)
			(size 0.4318 0.4318)
			(layers "F.Cu" "F.Mask" "F.Paste")
			(net "NC_CPU0_MDFI_DIE10_EW1")
		)
		(pad "CD32" smd circle
			(at -12.19454 2.529586 270)
			(size 0.4318 0.4318)
			(layers "F.Cu" "F.Mask" "F.Paste")
			(net "PVCCIN_CPU0")
		)
		(pad "CD34" smd circle
			(at -10.566654 2.529586 270)
			(size 0.4318 0.4318)
			(layers "F.Cu" "F.Mask" "F.Paste")
			(net "PVCCIN_CPU0")
		)
		(pad "CD36" smd circle
			(at -8.939022 2.529586 270)
			(size 0.4318 0.4318)
			(layers "F.Cu" "F.Mask" "F.Paste")
			(net "PVCCIN_CPU0")
		)
		(pad "CD38" smd circle
			(at -7.311136 2.529586 270)
			(size 0.4318 0.4318)
			(layers "F.Cu" "F.Mask" "F.Paste")
			(net "PVCCIN_CPU0")
		)
		(pad "CD40" smd circle
			(at -5.68325 2.529586 270)
			(size 0.4318 0.4318)
			(layers "F.Cu" "F.Mask" "F.Paste")
			(net "PVCCIN_CPU0")
		)
		(pad "CD42" smd circle
			(at -4.055618 2.529586 270)
			(size 0.4318 0.4318)
			(layers "F.Cu" "F.Mask" "F.Paste")
			(net "PVCCIN_CPU0")
		)
		(pad "CD44" smd circle
			(at -2.427732 2.529586 270)
			(size 0.4318 0.4318)
			(layers "F.Cu" "F.Mask" "F.Paste")
			(net "PVCCIN_CPU0")
		)
		(pad "CD47" smd circle
			(at 1.613916 2.639314 270)
			(size 0.4318 0.4318)
			(layers "F.Cu" "F.Mask" "F.Paste")
			(net "PVCCIN_CPU0")
		)
		(pad "CD49" smd circle
			(at 3.241802 2.639314 270)
			(size 0.4318 0.4318)
			(layers "F.Cu" "F.Mask" "F.Paste")
			(net "PVCCIN_CPU0")
		)
		(pad "CD51" smd circle
			(at 4.869434 2.639314 270)
			(size 0.4318 0.4318)
			(layers "F.Cu" "F.Mask" "F.Paste")
			(net "PVCCIN_CPU0")
		)
		(pad "CD53" smd circle
			(at 6.49732 2.639314 270)
			(size 0.4318 0.4318)
			(layers "F.Cu" "F.Mask" "F.Paste")
			(net "PVCCIN_CPU0")
		)
		(pad "CD55" smd circle
			(at 8.124952 2.639314 270)
			(size 0.4318 0.4318)
			(layers "F.Cu" "F.Mask" "F.Paste")
			(net "PVCCIN_CPU0")
		)
		(pad "CD57" smd circle
			(at 9.752838 2.639314 270)
			(size 0.4318 0.4318)
			(layers "F.Cu" "F.Mask" "F.Paste")
			(net "PVCCIN_CPU0")
		)
		(pad "CD59" smd circle
			(at 11.380724 2.639314 270)
			(size 0.4318 0.4318)
			(layers "F.Cu" "F.Mask" "F.Paste")
			(net "PVCCIN_CPU0")
		)
		(pad "CD61" smd circle
			(at 13.008356 2.639314 270)
			(size 0.4318 0.4318)
			(layers "F.Cu" "F.Mask" "F.Paste")
			(net "GND")
		)
		(pad "CD63" smd circle
			(at 14.635988 2.639314 270)
			(size 0.4318 0.4318)
			(layers "F.Cu" "F.Mask" "F.Paste")
			(net "SMB_S3M_CPU0_SDA")
		)
		(pad "CD65" smd circle
			(at 16.263874 2.639314 270)
			(size 0.4318 0.4318)
			(layers "F.Cu" "F.Mask" "F.Paste")
			(net "TP_SGPIO_S3M_CPU0_RST_R_N")
		)
		(pad "CD67" smd circle
			(at 17.89176 2.639314 270)
			(size 0.4318 0.4318)
			(layers "F.Cu" "F.Mask" "F.Paste")
			(net "PVPP_HBM_CPU0")
		)
		(pad "CD69" smd circle
			(at 19.519392 2.639314 270)
			(size 0.4318 0.4318)
			(layers "F.Cu" "F.Mask" "F.Paste")
			(net "TP_CPU0_SPARE11")
		)
		(pad "CD71" smd circle
			(at 21.147278 2.639314 270)
			(size 0.4318 0.4318)
			(layers "F.Cu" "F.Mask" "F.Paste")
			(net "NC_CLK_PFT_OUT_CPU0_DP")
		)
		(pad "CD73" smd circle
			(at 22.77491 2.639314 270)
			(size 0.4318 0.4318)
			(layers "F.Cu" "F.Mask" "F.Paste")
			(net "Net_661")
		)
		(pad "CD75" smd circle
			(at 24.402796 2.639314 270)
			(size 0.4318 0.4318)
			(layers "F.Cu" "F.Mask" "F.Paste")
			(net "GND")
		)
		(pad "CD77" smd circle
			(at 26.030682 2.639314 270)
			(size 0.4318 0.4318)
			(layers "F.Cu" "F.Mask" "F.Paste")
			(net "GND")
		)
		(pad "CD79" smd circle
			(at 27.658314 2.639314 270)
			(size 0.4318 0.4318)
			(layers "F.Cu" "F.Mask" "F.Paste")
			(net "PVCCIN_CPU0")
		)
		(pad "CD81" smd circle
			(at 29.2862 2.639314 270)
			(size 0.4318 0.4318)
			(layers "F.Cu" "F.Mask" "F.Paste")
			(net "PVCCIN_CPU0")
		)
		(pad "CD83" smd circle
			(at 30.914086 2.639314 270)
			(size 0.4318 0.4318)
			(layers "F.Cu" "F.Mask" "F.Paste")
			(net "PVCCIN_CPU0")
		)
		(pad "CD85" smd circle
			(at 32.541718 2.639314 270)
			(size 0.4318 0.4318)
			(layers "F.Cu" "F.Mask" "F.Paste")
			(net "PVCCIN_CPU0")
		)
		(pad "CD87" smd circle
			(at 34.169604 2.639314 270)
			(size 0.4318 0.4318)
			(layers "F.Cu" "F.Mask" "F.Paste")
			(net "PVCCIN_CPU0")
		)
		(pad "CD89" smd circle
			(at 35.797236 2.639314 270)
			(size 0.4318 0.4318)
			(layers "F.Cu" "F.Mask" "F.Paste")
			(net "PVCCIN_CPU0")
		)
		(pad "CE1" smd oval
			(at -37.425122 2.999486 180)
			(size 0.381 0.4826)
			(drill
				(offset 0 -0.0508)
			)
			(layers "F.Cu" "F.Mask" "F.Paste")
			(net "UPI_CPU1_CPU0_P0P1_DP<21>")
		)
		(pad "CE3" smd circle
			(at -35.797236 2.999486 270)
			(size 0.4318 0.4318)
			(layers "F.Cu" "F.Mask" "F.Paste")
			(net "GND")
		)
		(pad "CE5" smd circle
			(at -34.169604 2.999486 270)
			(size 0.4318 0.4318)
			(layers "F.Cu" "F.Mask" "F.Paste")
			(net "UPI_CPU0_CPU1_P1P0_DP<20>")
		)
		(pad "CE7" smd circle
			(at -32.541718 2.999486 270)
			(size 0.4318 0.4318)
			(layers "F.Cu" "F.Mask" "F.Paste")
			(net "PVCCD_HV_CPU0")
		)
		(pad "CE9" smd circle
			(at -30.914086 2.999486 270)
			(size 0.4318 0.4318)
			(layers "F.Cu" "F.Mask" "F.Paste")
			(net "P5E_CPU0_PE1_RX_DP<4>")
		)
		(pad "CE11" smd circle
			(at -29.2862 2.999486 270)
			(size 0.4318 0.4318)
			(layers "F.Cu" "F.Mask" "F.Paste")
			(net "VSENSE_PVCCINFAON_CPU0_DN")
		)
		(pad "CE13" smd circle
			(at -27.658314 2.999486 270)
			(size 0.4318 0.4318)
			(layers "F.Cu" "F.Mask" "F.Paste")
			(net "P5E_CPU0_PE1_TX_DN<5>")
		)
		(pad "CE15" smd circle
			(at -26.030682 2.999486 270)
			(size 0.4318 0.4318)
			(layers "F.Cu" "F.Mask" "F.Paste")
			(net "PVCCINFAON_CPU0")
		)
		(pad "CE17" smd circle
			(at -24.402796 2.999486 270)
			(size 0.4318 0.4318)
			(layers "F.Cu" "F.Mask" "F.Paste")
			(net "DMI_CPU0_PCH_TX_DP<3>")
		)
		(pad "CE19" smd circle
			(at -22.77491 2.999486 270)
			(size 0.4318 0.4318)
			(layers "F.Cu" "F.Mask" "F.Paste")
			(net "PVCCINFAON_CPU0")
		)
		(pad "CE21" smd circle
			(at -21.147278 2.999486 270)
			(size 0.4318 0.4318)
			(layers "F.Cu" "F.Mask" "F.Paste")
			(net "NC_CPU0_PE1_APROBE<0>")
		)
		(pad "CE23" smd circle
			(at -19.519392 2.999486 270)
			(size 0.4318 0.4318)
			(layers "F.Cu" "F.Mask" "F.Paste")
			(net "TP_H_SBLINK6_CPU0_PMDOWN")
		)
		(pad "CE25" smd circle
			(at -17.89176 2.999486 270)
			(size 0.4318 0.4318)
			(layers "F.Cu" "F.Mask" "F.Paste")
			(net "TP_H_SBLINK4_CPU0_PMSYNC")
		)
		(pad "CE60" smd circle
			(at 12.19454 3.109468 270)
			(size 0.4318 0.4318)
			(layers "F.Cu" "F.Mask" "F.Paste")
			(net "GND")
		)
		(pad "CE62" smd circle
			(at 13.822426 3.109468 270)
			(size 0.4318 0.4318)
			(layers "F.Cu" "F.Mask" "F.Paste")
			(net "NC_CPU0_LGSSPARE3")
		)
		(pad "CE64" smd circle
			(at 15.450058 3.109468 270)
			(size 0.4318 0.4318)
			(layers "F.Cu" "F.Mask" "F.Paste")
			(net "SMB_S3M_CPU0_SCL")
		)
		(pad "CE66" smd circle
			(at 17.07769 3.109468 270)
			(size 0.4318 0.4318)
			(layers "F.Cu" "F.Mask" "F.Paste")
			(net "GND")
		)
		(pad "CE68" smd circle
			(at 18.705576 3.109468 270)
			(size 0.4318 0.4318)
			(layers "F.Cu" "F.Mask" "F.Paste")
			(net "PVPP_HBM_CPU0")
		)
		(pad "CE70" smd circle
			(at 20.333462 3.109468 270)
			(size 0.4318 0.4318)
			(layers "F.Cu" "F.Mask" "F.Paste")
			(net "NC_CLK_PFT_OUT_CPU0_DN")
		)
		(pad "CE72" smd circle
			(at 21.961094 3.109468 270)
			(size 0.4318 0.4318)
			(layers "F.Cu" "F.Mask" "F.Paste")
			(net "GND")
		)
		(pad "CE74" smd circle
			(at 23.58898 3.109468 270)
			(size 0.4318 0.4318)
			(layers "F.Cu" "F.Mask" "F.Paste")
			(net "PVCCFA_EHV_FIVRA_CPU0")
		)
		(pad "CE76" smd circle
			(at 25.216612 3.109468 270)
			(size 0.4318 0.4318)
			(layers "F.Cu" "F.Mask" "F.Paste")
			(net "GND")
		)
		(pad "CE78" smd circle
			(at 26.844498 3.109468 270)
			(size 0.4318 0.4318)
			(layers "F.Cu" "F.Mask" "F.Paste")
			(net "GND")
		)
		(pad "CE80" smd circle
			(at 28.472384 3.109468 270)
			(size 0.4318 0.4318)
			(layers "F.Cu" "F.Mask" "F.Paste")
			(net "PVCCIN_CPU0")
		)
		(pad "CE82" smd circle
			(at 30.100016 3.109468 270)
			(size 0.4318 0.4318)
			(layers "F.Cu" "F.Mask" "F.Paste")
			(net "PVCCIN_CPU0")
		)
		(pad "CE84" smd circle
			(at 31.727902 3.109468 270)
			(size 0.4318 0.4318)
			(layers "F.Cu" "F.Mask" "F.Paste")
			(net "PVCCIN_CPU0")
		)
		(pad "CE86" smd circle
			(at 33.355534 3.109468 270)
			(size 0.4318 0.4318)
			(layers "F.Cu" "F.Mask" "F.Paste")
			(net "PVCCIN_CPU0")
		)
		(pad "CE88" smd circle
			(at 34.98342 3.109468 270)
			(size 0.4318 0.4318)
			(layers "F.Cu" "F.Mask" "F.Paste")
			(net "PVCCIN_CPU0")
		)
		(pad "CE90" smd oval
			(at 36.611306 3.109468)
			(size 0.381 0.4826)
			(drill
				(offset 0 -0.0508)
			)
			(layers "F.Cu" "F.Mask" "F.Paste")
			(net "PVCCIN_CPU0")
		)
		(pad "CF2" smd circle
			(at -36.611306 3.469132 270)
			(size 0.4318 0.4318)
			(layers "F.Cu" "F.Mask" "F.Paste")
			(net "UPI_CPU1_CPU0_P0P1_DN<21>")
		)
		(pad "CF4" smd circle
			(at -34.98342 3.469132 270)
			(size 0.4318 0.4318)
			(layers "F.Cu" "F.Mask" "F.Paste")
			(net "GND")
		)
		(pad "CF6" smd circle
			(at -33.355534 3.469132 270)
			(size 0.4318 0.4318)
			(layers "F.Cu" "F.Mask" "F.Paste")
			(net "UPI_CPU0_CPU1_P1P0_DN<20>")
		)
		(pad "CF8" smd circle
			(at -31.727902 3.469132 270)
			(size 0.4318 0.4318)
			(layers "F.Cu" "F.Mask" "F.Paste")
			(net "GND")
		)
		(pad "CF10" smd circle
			(at -30.100016 3.469132 270)
			(size 0.4318 0.4318)
			(layers "F.Cu" "F.Mask" "F.Paste")
			(net "P5E_CPU0_PE1_RX_DN<4>")
		)
		(pad "CF12" smd circle
			(at -28.472384 3.469132 270)
			(size 0.4318 0.4318)
			(layers "F.Cu" "F.Mask" "F.Paste")
			(net "GND")
		)
		(pad "CF14" smd circle
			(at -26.844498 3.469132 270)
			(size 0.4318 0.4318)
			(layers "F.Cu" "F.Mask" "F.Paste")
			(net "P5E_CPU0_PE1_TX_DN<4>")
		)
		(pad "CF16" smd circle
			(at -25.216612 3.469132 270)
			(size 0.4318 0.4318)
			(layers "F.Cu" "F.Mask" "F.Paste")
			(net "GND")
		)
		(pad "CF18" smd circle
			(at -23.58898 3.469132 270)
			(size 0.4318 0.4318)
			(layers "F.Cu" "F.Mask" "F.Paste")
			(net "DMI_CPU0_PCH_TX_DN<4>")
		)
		(pad "CF20" smd circle
			(at -21.961094 3.469132 270)
			(size 0.4318 0.4318)
			(layers "F.Cu" "F.Mask" "F.Paste")
			(net "GND")
		)
		(pad "CF22" smd circle
			(at -20.333462 3.469132 270)
			(size 0.4318 0.4318)
			(layers "F.Cu" "F.Mask" "F.Paste")
			(net "NC_CPU0_MDFI_DIE10_NS0")
		)
		(pad "CF24" smd circle
			(at -18.705576 3.469132 270)
			(size 0.4318 0.4318)
			(layers "F.Cu" "F.Mask" "F.Paste")
			(net "TP_H_SBLINK7_CPU0_PMSYNC")
		)
		(pad "CF26" smd circle
			(at -17.07769 3.469132 270)
			(size 0.4318 0.4318)
			(layers "F.Cu" "F.Mask" "F.Paste")
			(net "H_CPU0_MEMHOT_OUT_LVC1_R_N")
		)
		(pad "CF61" smd circle
			(at 13.008356 3.579114 270)
			(size 0.4318 0.4318)
			(layers "F.Cu" "F.Mask" "F.Paste")
			(net "PUD_PCH_BOOT_MODE_CPU0")
		)
		(pad "CF63" smd circle
			(at 14.635988 3.579114 270)
			(size 0.4318 0.4318)
			(layers "F.Cu" "F.Mask" "F.Paste")
			(net "TP_SGPIO_S3M_CPU0_GSXCLK_R")
		)
		(pad "CF65" smd circle
			(at 16.263874 3.579114 270)
			(size 0.4318 0.4318)
			(layers "F.Cu" "F.Mask" "F.Paste")
			(net "TP_SGPIO_S3M_CPU0_GSXDOUT_R")
		)
		(pad "CF67" smd circle
			(at 17.89176 3.579114 270)
			(size 0.4318 0.4318)
			(layers "F.Cu" "F.Mask" "F.Paste")
			(net "PVPP_HBM_CPU0")
		)
		(pad "CF69" smd circle
			(at 19.519392 3.579114 270)
			(size 0.4318 0.4318)
			(layers "F.Cu" "F.Mask" "F.Paste")
			(net "GND")
		)
		(pad "CF71" smd circle
			(at 21.147278 3.579114 270)
			(size 0.4318 0.4318)
			(layers "F.Cu" "F.Mask" "F.Paste")
			(net "GND")
		)
		(pad "CF73" smd circle
			(at 22.77491 3.579114 270)
			(size 0.4318 0.4318)
			(layers "F.Cu" "F.Mask" "F.Paste")
			(net "Net_685")
		)
		(pad "CF75" smd circle
			(at 24.402796 3.579114 270)
			(size 0.4318 0.4318)
			(layers "F.Cu" "F.Mask" "F.Paste")
			(net "Net_688")
		)
		(pad "CF77" smd circle
			(at 26.030682 3.579114 270)
			(size 0.4318 0.4318)
			(layers "F.Cu" "F.Mask" "F.Paste")
			(net "Net_666")
		)
		(pad "CF79" smd circle
			(at 27.658314 3.579114 270)
			(size 0.4318 0.4318)
			(layers "F.Cu" "F.Mask" "F.Paste")
			(net "PVCCIN_CPU0")
		)
		(pad "CF81" smd circle
			(at 29.2862 3.579114 270)
			(size 0.4318 0.4318)
			(layers "F.Cu" "F.Mask" "F.Paste")
			(net "PVCCIN_CPU0")
		)
		(pad "CF83" smd circle
			(at 30.914086 3.579114 270)
			(size 0.4318 0.4318)
			(layers "F.Cu" "F.Mask" "F.Paste")
			(net "PVCCIN_CPU0")
		)
		(pad "CF85" smd circle
			(at 32.541718 3.579114 270)
			(size 0.4318 0.4318)
			(layers "F.Cu" "F.Mask" "F.Paste")
			(net "PVCCIN_CPU0")
		)
		(pad "CF87" smd circle
			(at 34.169604 3.579114 270)
			(size 0.4318 0.4318)
			(layers "F.Cu" "F.Mask" "F.Paste")
			(net "PVCCIN_CPU0")
		)
		(pad "CF89" smd circle
			(at 35.797236 3.579114 270)
			(size 0.4318 0.4318)
			(layers "F.Cu" "F.Mask" "F.Paste")
			(net "PVCCIN_CPU0")
		)
		(pad "CF91" smd oval
			(at 37.425122 3.579114)
			(size 0.381 0.4826)
			(drill
				(offset 0 -0.0508)
			)
			(layers "F.Cu" "F.Mask" "F.Paste")
			(net "PVCCIN_CPU0")
		)
		(pad "CG1" smd oval
			(at -37.425122 3.939286 180)
			(size 0.381 0.4826)
			(drill
				(offset 0 -0.0508)
			)
			(layers "F.Cu" "F.Mask" "F.Paste")
			(net "GND")
		)
		(pad "CG3" smd circle
			(at -35.797236 3.939286 270)
			(size 0.4318 0.4318)
			(layers "F.Cu" "F.Mask" "F.Paste")
			(net "UPI_CPU1_CPU0_P0P1_DN<20>")
		)
		(pad "CG5" smd circle
			(at -34.169604 3.939286 270)
			(size 0.4318 0.4318)
			(layers "F.Cu" "F.Mask" "F.Paste")
			(net "GND")
		)
		(pad "CG7" smd circle
			(at -32.541718 3.939286 270)
			(size 0.4318 0.4318)
			(layers "F.Cu" "F.Mask" "F.Paste")
			(net "UPI_CPU0_CPU1_P1P0_DN<19>")
		)
		(pad "CG9" smd circle
			(at -30.914086 3.939286 270)
			(size 0.4318 0.4318)
			(layers "F.Cu" "F.Mask" "F.Paste")
			(net "GND")
		)
		(pad "CG11" smd circle
			(at -29.2862 3.939286 270)
			(size 0.4318 0.4318)
			(layers "F.Cu" "F.Mask" "F.Paste")
			(net "P5E_CPU0_PE1_RX_DN<3>")
		)
		(pad "CG13" smd circle
			(at -27.658314 3.939286 270)
			(size 0.4318 0.4318)
			(layers "F.Cu" "F.Mask" "F.Paste")
			(net "GND")
		)
		(pad "CG15" smd circle
			(at -26.030682 3.939286 270)
			(size 0.4318 0.4318)
			(layers "F.Cu" "F.Mask" "F.Paste")
			(net "P5E_CPU0_PE1_TX_DP<4>")
		)
		(pad "CG17" smd circle
			(at -24.402796 3.939286 270)
			(size 0.4318 0.4318)
			(layers "F.Cu" "F.Mask" "F.Paste")
			(net "GND")
		)
		(pad "CG19" smd circle
			(at -22.77491 3.939286 270)
			(size 0.4318 0.4318)
			(layers "F.Cu" "F.Mask" "F.Paste")
			(net "DMI_CPU0_PCH_TX_DP<4>")
		)
		(pad "CG21" smd circle
			(at -21.147278 3.939286 270)
			(size 0.4318 0.4318)
			(layers "F.Cu" "F.Mask" "F.Paste")
			(net "GND")
		)
		(pad "CG23" smd circle
			(at -19.519392 3.939286 270)
			(size 0.4318 0.4318)
			(layers "F.Cu" "F.Mask" "F.Paste")
			(net "GND")
		)
		(pad "CG25" smd circle
			(at -17.89176 3.939286 270)
			(size 0.4318 0.4318)
			(layers "F.Cu" "F.Mask" "F.Paste")
			(net "GND")
		)
		(pad "CG60" smd circle
			(at 12.19454 4.049268 270)
			(size 0.4318 0.4318)
			(layers "F.Cu" "F.Mask" "F.Paste")
			(net "TP_CPU0_SPARE10")
		)
		(pad "CG62" smd circle
			(at 13.822426 4.049268 270)
			(size 0.4318 0.4318)
			(layers "F.Cu" "F.Mask" "F.Paste")
			(net "GND")
		)
		(pad "CG64" smd circle
			(at 15.450058 4.049268 270)
			(size 0.4318 0.4318)
			(layers "F.Cu" "F.Mask" "F.Paste")
			(net "GND")
		)
		(pad "CG66" smd circle
			(at 17.07769 4.049268 270)
			(size 0.4318 0.4318)
			(layers "F.Cu" "F.Mask" "F.Paste")
			(net "FM_CPU0_SKTOCC_LVT3_N")
		)
	)
)
